# S9S_MB_2U (Grand Teton) — schematic netlist excerpt (pin names and nets, part order shuffled) for the footprints in the layout excerpt that follows; sources: Cadence DE-HDL packaged netlist, KiCad conversion of 03242023_DA0F0TMBIJ0_F0T_Motherboard_J_brd_V01_OCP.brd

U181  PCA9539RPW  IC  pkg TSSOP24XB  page 227
  INT  = PU_U181_INT
  A1  = TCA9539_0_ADD1
  RESET  = PU_RST_SMB_U181_N
  IO0_0  = RST_USB_HUB_N
  IO0_1  = RST_SWB_BIC_N
  IO0_2  = TP_TCA9539_0_P0_2
  IO0_3  = TP_TCA9539_0_P0_3
  IO0_4  = PRSNT_SWB_ISO_R1_N
  IO0_5  = GPU_PRSNT_N_ISO_R1
  IO0_6  = PRSNT_CABLE_GPU_B3_ISO_R1_N
  IO0_7  = PRSNT_CABLE_SWB_B2_ISO_R_N
  VSS  = GND
  IO1_0  = PRSNT_CABLE_GPU_A2_ISO_R1_N
  IO1_1  = PRSNT_CABLE_SWB_B1_ISO_R_N
  IO1_2  = GPU_BASE_ID0_R
  IO1_3  = GPU_BASE_ID1_R
  IO1_4  = GPU_PEX_STRAP0_R
  IO1_5  = GPU_PEX_STRAP1_R
  IO1_6  = PRSNT_CABLE_GPU_A1_ISO_R1_N
  IO1_7  = PRSNT_CABLE_GPU_A3_ISO_R_N
  A0  = TCA9539_0_ADD0
  SCL  = SMB_IOEXP_3V3AUX_SCL_R1
  SDA  = SMB_IOEXP_3V3AUX_SDA_R1
  VDD  = P3V3_AUX

(kicad_pcb
	(version 20260206)
	(generator "pcbnew")
	(generator_version "10.0")
	(general
		(thickness 1.6)
		(legacy_teardrops no)
	)
	(paper "A4")
	(title_block
		(title "03242023_DA0F0TMBIJ0_F0T_Motherboard_J_brd_V01_OCP.brd")
		(comment 1 "Grand Teton / footprints 1373-1373 of 6105")
	)
	(layers
		(0 "F.Cu" signal "TOP")
		(4 "In1.Cu" signal "GND")
		(6 "In2.Cu" signal "IN1")
		(8 "In3.Cu" signal "GND1")
		(10 "In4.Cu" signal "IN2")
		(12 "In5.Cu" signal "GND2")
		(14 "In6.Cu" signal "IN3")
		(16 "In7.Cu" signal "GND3")
		(18 "In8.Cu" signal "VCC")
		(20 "In9.Cu" signal "VCC1")
		(22 "In10.Cu" signal "GND4")
		(24 "In11.Cu" signal "IN4")
		(26 "In12.Cu" signal "GND5")
		(28 "In13.Cu" signal "IN5")
		(30 "In14.Cu" signal "GND6")
		(32 "In15.Cu" signal "IN6")
		(34 "In16.Cu" signal "GND7")
		(2 "B.Cu" signal "BOTTOM")
		(9 "F.Adhes" user "F.Adhesive")
		(11 "B.Adhes" user "B.Adhesive")
		(13 "F.Paste" user "Package Geometry/Pastemask Top")
		(15 "B.Paste" user "Package Geometry/Pastemask Bottom")
		(5 "F.SilkS" user "Ref Des/Silkscreen Top")
		(7 "B.SilkS" user "Ref Des/Silkscreen Bottom")
		(1 "F.Mask" user "Board Geometry/Soldermask Top")
		(3 "B.Mask" user "Board Geometry/Soldermask Bottom")
		(17 "Dwgs.User" user "User.Drawings")
		(19 "Cmts.User" user "User.Comments")
		(21 "Eco1.User" user "User.Eco1")
		(23 "Eco2.User" user "User.Eco2")
		(25 "Edge.Cuts" user "Board Geometry/Outline")
		(27 "Margin" user)
		(31 "F.CrtYd" user "Package Geometry/Place Bound Top")
		(29 "B.CrtYd" user "Package Geometry/Place Bound Bottom")
		(35 "F.Fab" user "Ref Des/Assembly Top")
		(33 "B.Fab" user "Ref Des/Assembly Bottom")
	)
	(footprint ""
		(layer "F.Cu")
		(at 17.314926 -417.202366 90)
		(property "Reference" "U181"
			(at 1.322324 -8.237728 0)
			(unlocked yes)
			(layer "F.SilkS")
			(effects
				(font
					(size 0.7874 0.5842)
					(thickness 0.1524)
				)
				(justify left)
			)
		)
		(property "Value" ""
			(at 0 0 90)
			(layer "F.Fab")
			(effects
				(font
					(size 1.27 1.27)
				)
			)
		)
		(duplicate_pad_numbers_are_jumpers no)
		(fp_line
			(start 2.097532 -3.949954)
			(end 1.409954 -3.949954)
			(stroke
				(width 0.1524)
				(type default)
			)
			(layer "F.SilkS")
		)
		(fp_line
			(start 1.409954 -3.949954)
			(end 0 -2.54)
			(stroke
				(width 0.1524)
				(type default)
			)
			(layer "F.SilkS")
		)
		(fp_line
			(start -1.409954 -3.949954)
			(end -2.097532 -3.949954)
			(stroke
				(width 0.1524)
				(type default)
			)
			(layer "F.SilkS")
		)
		(fp_line
			(start -2.097532 -3.949954)
			(end -2.097532 3.949954)
			(stroke
				(width 0.1524)
				(type default)
			)
			(layer "F.SilkS")
		)
		(fp_line
			(start 0 -2.54)
			(end -1.409954 -3.949954)
			(stroke
				(width 0.1524)
				(type default)
			)
			(layer "F.SilkS")
		)
		(fp_line
			(start 2.097532 3.949954)
			(end 2.097532 -3.949954)
			(stroke
				(width 0.1524)
				(type default)
			)
			(layer "F.SilkS")
		)
		(fp_line
			(start -2.097532 3.949954)
			(end 2.097532 3.949954)
			(stroke
				(width 0.1524)
				(type default)
			)
			(layer "F.SilkS")
		)
		(fp_poly
			(pts
				(xy -2.496312 -5.281168) (xy -3.004312 -4.265168) (xy -3.512312 -5.281168)
			)
			(stroke
				(width 0)
				(type default)
			)
			(fill yes)
			(layer "F.SilkS")
		)
		(fp_line
			(start 2.249932 -3.949954)
			(end -2.249932 -3.949954)
			(stroke
				(width 0.1)
				(type default)
			)
			(layer "F.Fab")
		)
		(fp_line
			(start -2.249932 -3.949954)
			(end -2.249932 3.949954)
			(stroke
				(width 0.1)
				(type default)
			)
			(layer "F.Fab")
		)
		(fp_line
			(start 2.249932 3.949954)
			(end 2.249932 -3.949954)
			(stroke
				(width 0.1)
				(type default)
			)
			(layer "F.Fab")
		)
		(fp_line
			(start -2.249932 3.949954)
			(end 2.249932 3.949954)
			(stroke
				(width 0.1)
				(type default)
			)
			(layer "F.Fab")
		)
		(fp_poly
			(pts
				(xy -4.7498 -4.182872) (xy -4.7498 -3.166872) (xy -3.7338 -3.674872)
			)
			(stroke
				(width 0)
				(type default)
			)
			(fill yes)
			(layer "F.Fab")
		)
		(pad "1" smd rect
			(at -2.925064 -3.674872)
			(size 0.6096 1.3716)
			(layers "F.Cu" "F.Mask" "F.Paste")
			(net "PU_U181_INT")
		)
		(pad "2" smd rect
			(at -2.925064 -2.925064)
			(size 0.4064 1.3716)
			(layers "F.Cu" "F.Mask" "F.Paste")
			(net "TCA9539_0_ADD1")
		)
		(pad "3" smd rect
			(at -2.925064 -2.275078)
			(size 0.4064 1.3716)
			(layers "F.Cu" "F.Mask" "F.Paste")
			(net "PU_RST_SMB_U181_N")
		)
		(pad "4" smd rect
			(at -2.925064 -1.625092)
			(size 0.4064 1.3716)
			(layers "F.Cu" "F.Mask" "F.Paste")
			(net "RST_USB_HUB_N")
		)
		(pad "5" smd rect
			(at -2.925064 -0.975106)
			(size 0.4064 1.3716)
			(layers "F.Cu" "F.Mask" "F.Paste")
			(net "RST_SWB_BIC_N")
		)
		(pad "6" smd rect
			(at -2.925064 -0.32512)
			(size 0.4064 1.3716)
			(layers "F.Cu" "F.Mask" "F.Paste")
			(net "TP_TCA9539_0_P0_2")
		)
		(pad "7" smd rect
			(at -2.925064 0.32512)
			(size 0.4064 1.3716)
			(layers "F.Cu" "F.Mask" "F.Paste")
			(net "TP_TCA9539_0_P0_3")
		)
		(pad "8" smd rect
			(at -2.925064 0.975106)
			(size 0.4064 1.3716)
			(layers "F.Cu" "F.Mask" "F.Paste")
			(net "PRSNT_SWB_ISO_R1_N")
		)
		(pad "9" smd rect
			(at -2.925064 1.625092)
			(size 0.4064 1.3716)
			(layers "F.Cu" "F.Mask" "F.Paste")
			(net "GPU_PRSNT_N_ISO_R1")
		)
		(pad "10" smd rect
			(at -2.925064 2.275078)
			(size 0.4064 1.3716)
			(layers "F.Cu" "F.Mask" "F.Paste")
			(net "PRSNT_CABLE_GPU_B3_ISO_R1_N")
		)
		(pad "11" smd rect
			(at -2.925064 2.925064)
			(size 0.4064 1.3716)
			(layers "F.Cu" "F.Mask" "F.Paste")
			(net "PRSNT_CABLE_SWB_B2_ISO_R_N")
		)
		(pad "12" smd rect
			(at -2.925064 3.674872)
			(size 0.6096 1.3716)
			(layers "F.Cu" "F.Mask" "F.Paste")
			(net "GND")
		)
		(pad "13" smd rect
			(at 2.925064 3.674872)
			(size 0.6096 1.3716)
			(layers "F.Cu" "F.Mask" "F.Paste")
			(net "PRSNT_CABLE_GPU_A2_ISO_R1_N")
		)
		(pad "14" smd rect
			(at 2.925064 2.925064)
			(size 0.4064 1.3716)
			(layers "F.Cu" "F.Mask" "F.Paste")
			(net "PRSNT_CABLE_SWB_B1_ISO_R_N")
		)
		(pad "15" smd rect
			(at 2.925064 2.275078)
			(size 0.4064 1.3716)
			(layers "F.Cu" "F.Mask" "F.Paste")
			(net "GPU_BASE_ID0_R")
		)
		(pad "16" smd rect
			(at 2.925064 1.625092)
			(size 0.4064 1.3716)
			(layers "F.Cu" "F.Mask" "F.Paste")
			(net "GPU_BASE_ID1_R")
		)
		(pad "17" smd rect
			(at 2.925064 0.975106)
			(size 0.4064 1.3716)
			(layers "F.Cu" "F.Mask" "F.Paste")
			(net "GPU_PEX_STRAP0_R")
		)
		(pad "18" smd rect
			(at 2.925064 0.32512)
			(size 0.4064 1.3716)
			(layers "F.Cu" "F.Mask" "F.Paste")
			(net "GPU_PEX_STRAP1_R")
		)
		(pad "19" smd rect
			(at 2.925064 -0.32512)
			(size 0.4064 1.3716)
			(layers "F.Cu" "F.Mask" "F.Paste")
			(net "PRSNT_CABLE_GPU_A1_ISO_R1_N")
		)
		(pad "20" smd rect
			(at 2.925064 -0.975106)
			(size 0.4064 1.3716)
			(layers "F.Cu" "F.Mask" "F.Paste")
			(net "PRSNT_CABLE_GPU_A3_ISO_R_N")
		)
		(pad "21" smd rect
			(at 2.925064 -1.625092)
			(size 0.4064 1.3716)
			(layers "F.Cu" "F.Mask" "F.Paste")
			(net "TCA9539_0_ADD0")
		)
		(pad "22" smd rect
			(at 2.925064 -2.275078)
			(size 0.4064 1.3716)
			(layers "F.Cu" "F.Mask" "F.Paste")
			(net "SMB_IOEXP_3V3AUX_SCL_R1")
		)
		(pad "23" smd rect
			(at 2.925064 -2.925064)
			(size 0.4064 1.3716)
			(layers "F.Cu" "F.Mask" "F.Paste")
			(net "SMB_IOEXP_3V3AUX_SDA_R1")
		)
		(pad "24" smd rect
			(at 2.925064 -3.674872)
			(size 0.6096 1.3716)
			(layers "F.Cu" "F.Mask" "F.Paste")
			(net "P3V3_AUX")
		)
	)
)
